FILE_TYPE = CONNECTIVITY;
{Allegro Design Entry HDL 17.4-2019 S026 (4007227) 1/17/2022}
"PAGE_NUMBER" = 368;
0"NC";
1"P3V3_AUX\g";
2"GND\g";
3"P3V3_AUX\g";
4"GND\g";
5"PWRGD_PS_PWROK_PLD_ISO";
6"PWRGD_PS_PWROK_PLD";
7"PWRGD_PS_PWROK_PLD_N";
8"PWRGD_PS_PWROK_PLD_ISO_R";
9"MB0_P12V_STBY_PWRGD"CDS_PHYS_NET_NAME"MB0_P12V_STBY_PWRGD";
10"PWRGD_PS_PWROK";
11"PWRGD_PS_PWROK_PLD"CDS_PHYS_NET_NAME"PWRGD_PS_PWROK_PLD";
%"MOSFET_NCH_DUAL"
"2","(-4825,4200)","0","pure_quanta","I10";
;
LOCATION"Q144"
$SEC"2"
CDS_SEC"2"
VALUE"PJT138K"
MATERIAL"IC"
PART_TYPE"SMLF"
CDS_LIB"pure_quanta"
NEEDS_NO_SIZE"TRUE"
CDS_LMAN_SYM_OUTLINE"-150,150,150,-150"
PART_NUMBER"BAM138K0003";
"S2"
$PN"4"4;
"G2"
$PN"5"7;
"D2"
$PN"3"5;
%"Q_RES"
"2","(-4775,4625)","0","pure_quanta","I11";
;
LOCATION"R4605"
$SEC"1"
CDS_SEC"1"
TOLERANCE"1%"
VALUE"1K"
WATTAGE"1/16W"
MATERIAL"CHIP"
PACK_TYPE"0402LF"
CDS_LIB"pure_quanta"
PART_NUMBER"CS21002FB06";
"A"
$PN"1"1;
"B"
$PN"2"5;
%"UNIVERSAL_POWER"
"1","(-4775,4850)","0","pure_quanta_power","I12";
;
HDL_POWER"P3V3_AUX"
CDS_LIB"pure_quanta_power";
"A"1;
%"Q_RES"
"1","(-3500,4450)","0","pure_quanta","I13";
;
LOCATION"R9446"
$SEC"1"
CDS_SEC"1"
MATERIAL"CHIP"
WATTAGE"1/16W"
PACK_TYPE"0402LF"
TOLERANCE"1%"
VALUE"33.2"
CDS_LIB"pure_quanta"
PART_NUMBER"CS03322FB03";
"B"
$PN"2"8;
"A"
$PN"1"5;
%"MOSFET_NCH_DUAL"
"1","(-5975,3900)","0","pure_quanta","I3";
;
LOCATION"Q144"
$SEC"1"
CDS_SEC"1"
PART_TYPE"SMLF"
VALUE"PJT138K"
MATERIAL"IC"
CDS_LMAN_SYM_OUTLINE"-150,150,150,-150"
NEEDS_NO_SIZE"TRUE"
CDS_LIB"pure_quanta"
PART_NUMBER"BAM138K0003";
"D1"
$PN"6"7;
"G1"
$PN"2"6;
"S1"
$PN"1"2;
%"UNIVERSAL_GND"
"1","(-5925,3525)","0","pure_quanta_power","I4";
;
CDS_LIB"pure_quanta_power"
HDL_POWER"GND";
"A"2;
%"Q_RES"
"2","(-5925,4500)","0","pure_quanta","I5";
;
LOCATION"R4604"
$SEC"1"
CDS_SEC"1"
TOLERANCE"5%"
VALUE"4.7K"
MATERIAL"CHIP"
WATTAGE"1/16W"
PACK_TYPE"0402LF"
CDS_LIB"pure_quanta"
PART_NUMBER"CS24702JB10";
"A"
$PN"1"3;
"B"
$PN"2"7;
%"UNIVERSAL_POWER"
"1","(-5925,4725)","0","pure_quanta_power","I6";
;
HDL_POWER"P3V3_AUX"
CDS_LIB"pure_quanta_power";
"A"3;
%"Q_RES"
"1","(-4550,2575)","0","pure_quanta","I7";
;
LOCATION"R3048"
$SEC"1"
CDS_SEC"1"
MATERIAL"CHIP"
TOLERANCE"5%"
VALUE"0"
WATTAGE"1/16W"
PACK_TYPE"0402LF"
CDS_LIB"pure_quanta"
PART_NUMBER"CS00002JB13";
"B"
$PN"2"10;
"A"
$PN"1"9;
%"Q_RES"
"1","(-4550,2750)","0","pure_quanta","I8";
;
LOCATION"R3047"
$SEC"1"
CDS_SEC"1"
VALUE"0"
TOLERANCE"5%"
MATERIAL"CHIP"
CDS_LIB"pure_quanta"
PACK_TYPE"0402LF"
WATTAGE"1/16W"
PART_NUMBER"CS00002JB13";
"B"
$PN"2"11;
"A"
$PN"1"9;
%"UNIVERSAL_GND"
"1","(-4775,3825)","0","pure_quanta_power","I9";
;
CDS_LIB"pure_quanta_power"
HDL_POWER"GND";
"A"4;
END.
